(kicad_pcb
	(version 20260206)
	(generator "pcbnew")
	(generator_version "10.0")
	(general
		(thickness 1.6)
		(legacy_teardrops no)
	)
	(paper "A4")
	(title_block
		(title "peb — Lightning_PEB_BRD.brd")
		(comment 1 "Lightning (Wiwynn / Facebook NVMe JBOF) / footprints 1237-1243 of 2563")
	)
	(layers
		(0 "F.Cu" signal "TOP")
		(4 "In1.Cu" signal "L2GND")
		(6 "In2.Cu" signal "L3")
		(8 "In3.Cu" signal "L4VCC")
		(10 "In4.Cu" signal "L5VCC")
		(12 "In5.Cu" signal "L6")
		(14 "In6.Cu" signal "L7GND")
		(2 "B.Cu" signal "BOTTOM")
		(9 "F.Adhes" user "F.Adhesive")
		(11 "B.Adhes" user "B.Adhesive")
		(13 "F.Paste" user "Package Geometry/Pastemask Top")
		(15 "B.Paste" user "Package Geometry/Pastemask Bottom")
		(5 "F.SilkS" user "Ref Des/Silkscreen Top")
		(7 "B.SilkS" user "Ref Des/Silkscreen Bottom")
		(1 "F.Mask" user "Board Geometry/Soldermask Top")
		(3 "B.Mask" user "Board Geometry/Soldermask Bottom")
		(17 "Dwgs.User" user "User.Drawings")
		(19 "Cmts.User" user "User.Comments")
		(21 "Eco1.User" user "User.Eco1")
		(23 "Eco2.User" user "User.Eco2")
		(25 "Edge.Cuts" user "Board Geometry/Outline")
		(27 "Margin" user)
		(31 "F.CrtYd" user "Package Geometry/Place Bound Top")
		(29 "B.CrtYd" user "Package Geometry/Place Bound Bottom")
		(35 "F.Fab" user "Ref Des/Assembly Top")
		(33 "B.Fab" user "Ref Des/Assembly Bottom")
	)
	(footprint ""
		(layer "F.Cu")
		(at 56.261 -119.126 90)
		(property "Reference" "R580"
			(at 0 0 90)
			(layer "F.SilkS")
			(hide yes)
			(effects
				(font
					(size 1.27 1.27)
				)
			)
		)
		(property "Value" "4K7R2F-GP"
			(at 0.064008 -3.993896 90)
			(unlocked yes)
			(layer "F.Fab")
			(hide yes)
			(effects
				(font
					(size 1.016 1.016)
					(thickness 0.1524)
				)
			)
		)
		(property "Device Type" "R402H16"
			(at 0.064008 -5.517896 90)
			(unlocked yes)
			(layer "F.Fab")
			(hide yes)
			(effects
				(font
					(size 1.016 1.016)
					(thickness 0.1524)
				)
			)
		)
		(duplicate_pad_numbers_are_jumpers no)
		(fp_line
			(start 0.508 -0.9398)
			(end -0.508 -0.9398)
			(stroke
				(width 0.1524)
				(type default)
			)
			(layer "F.SilkS")
		)
		(fp_line
			(start -0.508 -0.9398)
			(end -0.508 0.9398)
			(stroke
				(width 0.1524)
				(type default)
			)
			(layer "F.SilkS")
		)
		(fp_rect
			(start -0.508 0.9398)
			(end 0.508 -0.9398)
			(stroke
				(width 0)
				(type default)
			)
			(fill no)
			(layer "F.CrtYd")
		)
		(fp_rect
			(start -0.508 0.9398)
			(end 0.508 -0.9398)
			(stroke
				(width 0)
				(type default)
			)
			(fill no)
			(layer "F.Fab")
		)
		(pad "1" smd custom
			(at 0 -0.4445 90)
			(size 0.1397 0.1397)
			(layers "F.Cu" "F.Mask" "F.Paste")
			(net "BMC_I2C7_B_DBP_SCL")
			(options
				(clearance outline)
				(anchor circle)
			)
			(primitives
				(gr_poly
					(pts
						(arc
							(start -0.1778 -0.2794)
							(mid -0.249642 -0.249642)
							(end -0.2794 -0.1778)
						)
						(arc
							(start -0.2794 0.1778)
							(mid -0.249642 0.249642)
							(end -0.1778 0.2794)
						)
						(arc
							(start 0.1778 0.2794)
							(mid 0.249642 0.249642)
							(end 0.2794 0.1778)
						)
						(arc
							(start 0.2794 -0.1778)
							(mid 0.249642 -0.249642)
							(end 0.1778 -0.2794)
						)
					)
					(width 0)
					(fill yes)
				)
			)
		)
		(pad "2" smd custom
			(at 0 0.4445 90)
			(size 0.1397 0.1397)
			(layers "F.Cu" "F.Mask" "F.Paste")
			(net "P3V3_STBY")
			(options
				(clearance outline)
				(anchor circle)
			)
			(primitives
				(gr_poly
					(pts
						(arc
							(start -0.1778 -0.2794)
							(mid -0.249642 -0.249642)
							(end -0.2794 -0.1778)
						)
						(arc
							(start -0.2794 0.1778)
							(mid -0.249642 0.249642)
							(end -0.1778 0.2794)
						)
						(arc
							(start 0.1778 0.2794)
							(mid 0.249642 0.249642)
							(end 0.2794 0.1778)
						)
						(arc
							(start 0.2794 -0.1778)
							(mid 0.249642 -0.249642)
							(end 0.1778 -0.2794)
						)
					)
					(width 0)
					(fill yes)
				)
			)
		)
	)
	(footprint ""
		(layer "F.Cu")
		(at 133.1214 -86.487 -90)
		(property "Reference" "R655"
			(at 0 0 270)
			(layer "F.SilkS")
			(hide yes)
			(effects
				(font
					(size 1.27 1.27)
				)
			)
		)
		(property "Value" "4K7R2F-GP"
			(at 0.064008 -3.993896 270)
			(unlocked yes)
			(layer "F.Fab")
			(hide yes)
			(effects
				(font
					(size 1.016 1.016)
					(thickness 0.1524)
				)
			)
		)
		(property "Device Type" "R402H16"
			(at 0.064008 -5.517896 270)
			(unlocked yes)
			(layer "F.Fab")
			(hide yes)
			(effects
				(font
					(size 1.016 1.016)
					(thickness 0.1524)
				)
			)
		)
		(duplicate_pad_numbers_are_jumpers no)
		(fp_line
			(start -0.508 -0.9398)
			(end -0.508 0.9398)
			(stroke
				(width 0.1524)
				(type default)
			)
			(layer "F.SilkS")
		)
		(fp_line
			(start 0.508 -0.9398)
			(end -0.508 -0.9398)
			(stroke
				(width 0.1524)
				(type default)
			)
			(layer "F.SilkS")
		)
		(fp_rect
			(start -0.508 0.9398)
			(end 0.508 -0.9398)
			(stroke
				(width 0)
				(type default)
			)
			(fill no)
			(layer "F.CrtYd")
		)
		(fp_rect
			(start -0.508 0.9398)
			(end 0.508 -0.9398)
			(stroke
				(width 0)
				(type default)
			)
			(fill no)
			(layer "F.Fab")
		)
		(pad "1" smd custom
			(at 0 -0.4445 270)
			(size 0.1397 0.1397)
			(layers "F.Cu" "F.Mask" "F.Paste")
			(net "P3V3_RTC")
			(options
				(clearance outline)
				(anchor circle)
			)
			(primitives
				(gr_poly
					(pts
						(arc
							(start -0.1778 -0.2794)
							(mid -0.249642 -0.249642)
							(end -0.2794 -0.1778)
						)
						(arc
							(start -0.2794 0.1778)
							(mid -0.249642 0.249642)
							(end -0.1778 0.2794)
						)
						(arc
							(start 0.1778 0.2794)
							(mid 0.249642 0.249642)
							(end 0.2794 0.1778)
						)
						(arc
							(start 0.2794 -0.1778)
							(mid 0.249642 -0.249642)
							(end 0.1778 -0.2794)
						)
					)
					(width 0)
					(fill yes)
				)
			)
		)
		(pad "2" smd custom
			(at 0 0.4445 270)
			(size 0.1397 0.1397)
			(layers "F.Cu" "F.Mask" "F.Paste")
			(net "RTC_INT_N")
			(options
				(clearance outline)
				(anchor circle)
			)
			(primitives
				(gr_poly
					(pts
						(arc
							(start -0.1778 -0.2794)
							(mid -0.249642 -0.249642)
							(end -0.2794 -0.1778)
						)
						(arc
							(start -0.2794 0.1778)
							(mid -0.249642 0.249642)
							(end -0.1778 0.2794)
						)
						(arc
							(start 0.1778 0.2794)
							(mid 0.249642 0.249642)
							(end 0.2794 0.1778)
						)
						(arc
							(start 0.2794 -0.1778)
							(mid 0.249642 -0.249642)
							(end 0.1778 -0.2794)
						)
					)
					(width 0)
					(fill yes)
				)
			)
		)
	)
	(footprint ""
		(layer "F.Cu")
		(at 230.251 -7.366 90)
		(property "Reference" "R952"
			(at 0 0 90)
			(layer "F.SilkS")
			(hide yes)
			(effects
				(font
					(size 1.27 1.27)
				)
			)
		)
		(property "Value" "0R2J-2-GP"
			(at 0.064008 -3.993896 90)
			(unlocked yes)
			(layer "F.Fab")
			(hide yes)
			(effects
				(font
					(size 1.016 1.016)
					(thickness 0.1524)
				)
			)
		)
		(property "Device Type" "R402H16"
			(at 0.064008 -5.517896 90)
			(unlocked yes)
			(layer "F.Fab")
			(hide yes)
			(effects
				(font
					(size 1.016 1.016)
					(thickness 0.1524)
				)
			)
		)
		(duplicate_pad_numbers_are_jumpers no)
		(fp_line
			(start 0.508 -0.9398)
			(end -0.508 -0.9398)
			(stroke
				(width 0.1524)
				(type default)
			)
			(layer "F.SilkS")
		)
		(fp_line
			(start -0.508 -0.9398)
			(end -0.508 0.9398)
			(stroke
				(width 0.1524)
				(type default)
			)
			(layer "F.SilkS")
		)
		(fp_rect
			(start -0.508 0.9398)
			(end 0.508 -0.9398)
			(stroke
				(width 0)
				(type default)
			)
			(fill no)
			(layer "F.CrtYd")
		)
		(fp_rect
			(start -0.508 0.9398)
			(end 0.508 -0.9398)
			(stroke
				(width 0)
				(type default)
			)
			(fill no)
			(layer "F.Fab")
		)
		(pad "1" smd custom
			(at 0 -0.4445 90)
			(size 0.1397 0.1397)
			(layers "F.Cu" "F.Mask" "F.Paste")
			(net "TWI_SDA2_R")
			(options
				(clearance outline)
				(anchor circle)
			)
			(primitives
				(gr_poly
					(pts
						(arc
							(start -0.1778 -0.2794)
							(mid -0.249642 -0.249642)
							(end -0.2794 -0.1778)
						)
						(arc
							(start -0.2794 0.1778)
							(mid -0.249642 0.249642)
							(end -0.1778 0.2794)
						)
						(arc
							(start 0.1778 0.2794)
							(mid 0.249642 0.249642)
							(end 0.2794 0.1778)
						)
						(arc
							(start 0.2794 -0.1778)
							(mid 0.249642 -0.249642)
							(end 0.1778 -0.2794)
						)
					)
					(width 0)
					(fill yes)
				)
			)
		)
		(pad "2" smd custom
			(at 0 0.4445 90)
			(size 0.1397 0.1397)
			(layers "F.Cu" "F.Mask" "F.Paste")
			(net "TWI_SDA2")
			(options
				(clearance outline)
				(anchor circle)
			)
			(primitives
				(gr_poly
					(pts
						(arc
							(start -0.1778 -0.2794)
							(mid -0.249642 -0.249642)
							(end -0.2794 -0.1778)
						)
						(arc
							(start -0.2794 0.1778)
							(mid -0.249642 0.249642)
							(end -0.1778 0.2794)
						)
						(arc
							(start 0.1778 0.2794)
							(mid 0.249642 0.249642)
							(end 0.2794 0.1778)
						)
						(arc
							(start 0.2794 -0.1778)
							(mid 0.249642 -0.249642)
							(end 0.1778 -0.2794)
						)
					)
					(width 0)
					(fill yes)
				)
			)
		)
	)
	(footprint ""
		(layer "F.Cu")
		(at 32.55772 -79.429356)
		(property "Reference" "PR65"
			(at 0 0 0)
			(layer "F.SilkS")
			(hide yes)
			(effects
				(font
					(size 1.27 1.27)
				)
			)
		)
		(property "Value" "100KR2F-L1-GP"
			(at 0.064008 -3.993896 0)
			(unlocked yes)
			(layer "F.Fab")
			(hide yes)
			(effects
				(font
					(size 1.016 1.016)
					(thickness 0.1524)
				)
			)
		)
		(property "Device Type" "R402H16"
			(at 0.064008 -5.517896 0)
			(unlocked yes)
			(layer "F.Fab")
			(hide yes)
			(effects
				(font
					(size 1.016 1.016)
					(thickness 0.1524)
				)
			)
		)
		(duplicate_pad_numbers_are_jumpers no)
		(fp_line
			(start -0.508 -0.9398)
			(end -0.508 0.9398)
			(stroke
				(width 0.1524)
				(type default)
			)
			(layer "F.SilkS")
		)
		(fp_line
			(start 0.508 -0.9398)
			(end -0.508 -0.9398)
			(stroke
				(width 0.1524)
				(type default)
			)
			(layer "F.SilkS")
		)
		(fp_rect
			(start -0.508 0.9398)
			(end 0.508 -0.9398)
			(stroke
				(width 0)
				(type default)
			)
			(fill no)
			(layer "F.CrtYd")
		)
		(fp_rect
			(start -0.508 0.9398)
			(end 0.508 -0.9398)
			(stroke
				(width 0)
				(type default)
			)
			(fill no)
			(layer "F.Fab")
		)
		(pad "1" smd custom
			(at 0 -0.4445)
			(size 0.1397 0.1397)
			(layers "F.Cu" "F.Mask" "F.Paste")
			(net "P5V_STBY_LR")
			(options
				(clearance outline)
				(anchor circle)
			)
			(primitives
				(gr_poly
					(pts
						(arc
							(start -0.1778 -0.2794)
							(mid -0.249642 -0.249642)
							(end -0.2794 -0.1778)
						)
						(arc
							(start -0.2794 0.1778)
							(mid -0.249642 0.249642)
							(end -0.1778 0.2794)
						)
						(arc
							(start 0.1778 0.2794)
							(mid 0.249642 0.249642)
							(end 0.2794 0.1778)
						)
						(arc
							(start 0.2794 -0.1778)
							(mid 0.249642 -0.249642)
							(end 0.1778 -0.2794)
						)
					)
					(width 0)
					(fill yes)
				)
			)
		)
		(pad "2" smd custom
			(at 0 0.4445)
			(size 0.1397 0.1397)
			(layers "F.Cu" "F.Mask" "F.Paste")
			(net "P5V_STBY_FB")
			(options
				(clearance outline)
				(anchor circle)
			)
			(primitives
				(gr_poly
					(pts
						(arc
							(start -0.1778 -0.2794)
							(mid -0.249642 -0.249642)
							(end -0.2794 -0.1778)
						)
						(arc
							(start -0.2794 0.1778)
							(mid -0.249642 0.249642)
							(end -0.1778 0.2794)
						)
						(arc
							(start 0.1778 0.2794)
							(mid 0.249642 0.249642)
							(end 0.2794 0.1778)
						)
						(arc
							(start 0.2794 -0.1778)
							(mid 0.249642 -0.249642)
							(end 0.1778 -0.2794)
						)
					)
					(width 0)
					(fill yes)
				)
			)
		)
	)
	(footprint ""
		(layer "F.Cu")
		(at 69.991986 -212.420454 180)
		(property "Reference" "C353"
			(at 0 0 180)
			(layer "F.SilkS")
			(hide yes)
			(effects
				(font
					(size 1.27 1.27)
				)
			)
		)
		(property "Value" "SCD22U10V2KX-1GP"
			(at 1.1811 -2.7051 180)
			(unlocked yes)
			(layer "F.Fab")
			(hide yes)
			(effects
				(font
					(size 1.016 1.016)
					(thickness 0.1524)
				)
			)
		)
		(property "Device Type" "C402H22"
			(at 1.1811 -4.2291 180)
			(unlocked yes)
			(layer "F.Fab")
			(hide yes)
			(effects
				(font
					(size 1.016 1.016)
					(thickness 0.1524)
				)
			)
		)
		(duplicate_pad_numbers_are_jumpers no)
		(fp_rect
			(start -0.4318 0.9525)
			(end 0.4318 -0.9525)
			(stroke
				(width 0)
				(type default)
			)
			(fill no)
			(layer "F.CrtYd")
		)
		(fp_rect
			(start -0.4318 0.9525)
			(end 0.4318 -0.9525)
			(stroke
				(width 0)
				(type default)
			)
			(fill no)
			(layer "F.Fab")
		)
		(pad "1" smd custom
			(at 0 -0.4445 180)
			(size 0.1524 0.1524)
			(layers "F.Cu" "F.Mask" "F.Paste")
			(net "PCIE_TX_CAP_P69")
			(options
				(clearance outline)
				(anchor circle)
			)
			(primitives
				(gr_poly
					(pts
						(arc
							(start 0.3048 -0.2032)
							(mid 0.275042 -0.275042)
							(end 0.2032 -0.3048)
						)
						(arc
							(start -0.2032 -0.3048)
							(mid -0.275042 -0.275042)
							(end -0.3048 -0.2032)
						)
						(arc
							(start -0.3048 0.2032)
							(mid -0.275042 0.275042)
							(end -0.2032 0.3048)
						)
						(arc
							(start 0.2032 0.3048)
							(mid 0.275042 0.275042)
							(end 0.3048 0.2032)
						)
					)
					(width 0)
					(fill yes)
				)
			)
		)
		(pad "2" smd custom
			(at 0 0.4445 180)
			(size 0.1524 0.1524)
			(layers "F.Cu" "F.Mask" "F.Paste")
			(net "PCIE_TX_P69")
			(options
				(clearance outline)
				(anchor circle)
			)
			(primitives
				(gr_poly
					(pts
						(arc
							(start 0.3048 -0.2032)
							(mid 0.275042 -0.275042)
							(end 0.2032 -0.3048)
						)
						(arc
							(start -0.2032 -0.3048)
							(mid -0.275042 -0.275042)
							(end -0.3048 -0.2032)
						)
						(arc
							(start -0.3048 0.2032)
							(mid -0.275042 0.275042)
							(end -0.2032 0.3048)
						)
						(arc
							(start 0.2032 0.3048)
							(mid 0.275042 0.275042)
							(end 0.3048 0.2032)
						)
					)
					(width 0)
					(fill yes)
				)
			)
		)
	)
	(footprint ""
		(layer "F.Cu")
		(at 335.026 -74.676 90)
		(property "Reference" "PR161"
			(at 0 0 90)
			(layer "F.SilkS")
			(hide yes)
			(effects
				(font
					(size 1.27 1.27)
				)
			)
		)
		(property "Value" "4K42R2F-GP"
			(at 0.064008 -3.993896 90)
			(unlocked yes)
			(layer "F.Fab")
			(hide yes)
			(effects
				(font
					(size 1.016 1.016)
					(thickness 0.1524)
				)
			)
		)
		(property "Device Type" "R402H16"
			(at 0.064008 -5.517896 90)
			(unlocked yes)
			(layer "F.Fab")
			(hide yes)
			(effects
				(font
					(size 1.016 1.016)
					(thickness 0.1524)
				)
			)
		)
		(duplicate_pad_numbers_are_jumpers no)
		(fp_line
			(start 0.508 -0.9398)
			(end -0.508 -0.9398)
			(stroke
				(width 0.1524)
				(type default)
			)
			(layer "F.SilkS")
		)
		(fp_line
			(start -0.508 -0.9398)
			(end -0.508 0.9398)
			(stroke
				(width 0.1524)
				(type default)
			)
			(layer "F.SilkS")
		)
		(fp_rect
			(start -0.508 0.9398)
			(end 0.508 -0.9398)
			(stroke
				(width 0)
				(type default)
			)
			(fill no)
			(layer "F.CrtYd")
		)
		(fp_rect
			(start -0.508 0.9398)
			(end 0.508 -0.9398)
			(stroke
				(width 0)
				(type default)
			)
			(fill no)
			(layer "F.Fab")
		)
		(pad "1" smd custom
			(at 0 -0.4445 90)
			(size 0.1397 0.1397)
			(layers "F.Cu" "F.Mask" "F.Paste")
			(net "P0V9_E_VFB_R")
			(options
				(clearance outline)
				(anchor circle)
			)
			(primitives
				(gr_poly
					(pts
						(arc
							(start -0.1778 -0.2794)
							(mid -0.249642 -0.249642)
							(end -0.2794 -0.1778)
						)
						(arc
							(start -0.2794 0.1778)
							(mid -0.249642 0.249642)
							(end -0.1778 0.2794)
						)
						(arc
							(start 0.1778 0.2794)
							(mid 0.249642 0.249642)
							(end 0.2794 0.1778)
						)
						(arc
							(start 0.2794 -0.1778)
							(mid 0.249642 -0.249642)
							(end 0.1778 -0.2794)
						)
					)
					(width 0)
					(fill yes)
				)
			)
		)
		(pad "2" smd custom
			(at 0 0.4445 90)
			(size 0.1397 0.1397)
			(layers "F.Cu" "F.Mask" "F.Paste")
			(net "P0V9_E_VFB")
			(options
				(clearance outline)
				(anchor circle)
			)
			(primitives
				(gr_poly
					(pts
						(arc
							(start -0.1778 -0.2794)
							(mid -0.249642 -0.249642)
							(end -0.2794 -0.1778)
						)
						(arc
							(start -0.2794 0.1778)
							(mid -0.249642 0.249642)
							(end -0.1778 0.2794)
						)
						(arc
							(start 0.1778 0.2794)
							(mid 0.249642 0.249642)
							(end 0.2794 0.1778)
						)
						(arc
							(start 0.2794 -0.1778)
							(mid 0.249642 -0.249642)
							(end 0.1778 -0.2794)
						)
					)
					(width 0)
					(fill yes)
				)
			)
		)
	)
	(footprint ""
		(layer "F.Cu")
		(at 207.408018 -212.420454 180)
		(property "Reference" "C112"
			(at 0 0 180)
			(layer "F.SilkS")
			(hide yes)
			(effects
				(font
					(size 1.27 1.27)
				)
			)
		)
		(property "Value" "SCD22U10V2KX-1GP"
			(at 1.1811 -2.7051 180)
			(unlocked yes)
			(layer "F.Fab")
			(hide yes)
			(effects
				(font
					(size 1.016 1.016)
					(thickness 0.1524)
				)
			)
		)
		(property "Device Type" "C402H22"
			(at 1.1811 -4.2291 180)
			(unlocked yes)
			(layer "F.Fab")
			(hide yes)
			(effects
				(font
					(size 1.016 1.016)
					(thickness 0.1524)
				)
			)
		)
		(duplicate_pad_numbers_are_jumpers no)
		(fp_rect
			(start -0.4318 0.9525)
			(end 0.4318 -0.9525)
			(stroke
				(width 0)
				(type default)
			)
			(fill no)
			(layer "F.CrtYd")
		)
		(fp_rect
			(start -0.4318 0.9525)
			(end 0.4318 -0.9525)
			(stroke
				(width 0)
				(type default)
			)
			(fill no)
			(layer "F.Fab")
		)
		(pad "1" smd custom
			(at 0 -0.4445 180)
			(size 0.1524 0.1524)
			(layers "F.Cu" "F.Mask" "F.Paste")
			(net "PCIE_TX_CAP_N40")
			(options
				(clearance outline)
				(anchor circle)
			)
			(primitives
				(gr_poly
					(pts
						(arc
							(start 0.3048 -0.2032)
							(mid 0.275042 -0.275042)
							(end 0.2032 -0.3048)
						)
						(arc
							(start -0.2032 -0.3048)
							(mid -0.275042 -0.275042)
							(end -0.3048 -0.2032)
						)
						(arc
							(start -0.3048 0.2032)
							(mid -0.275042 0.275042)
							(end -0.2032 0.3048)
						)
						(arc
							(start 0.2032 0.3048)
							(mid 0.275042 0.275042)
							(end 0.3048 0.2032)
						)
					)
					(width 0)
					(fill yes)
				)
			)
		)
		(pad "2" smd custom
			(at 0 0.4445 180)
			(size 0.1524 0.1524)
			(layers "F.Cu" "F.Mask" "F.Paste")
			(net "PCIE_TX_N40")
			(options
				(clearance outline)
				(anchor circle)
			)
			(primitives
				(gr_poly
					(pts
						(arc
							(start 0.3048 -0.2032)
							(mid 0.275042 -0.275042)
							(end 0.2032 -0.3048)
						)
						(arc
							(start -0.2032 -0.3048)
							(mid -0.275042 -0.275042)
							(end -0.3048 -0.2032)
						)
						(arc
							(start -0.3048 0.2032)
							(mid -0.275042 0.275042)
							(end -0.2032 0.3048)
						)
						(arc
							(start 0.2032 0.3048)
							(mid 0.275042 0.275042)
							(end 0.3048 0.2032)
						)
					)
					(width 0)
					(fill yes)
				)
			)
		)
	)
)
